(kicad_pcb
	(version 20260206)
	(generator "pcbnew")
	(generator_version "10.0")
	(general
		(thickness 1.6)
		(legacy_teardrops no)
	)
	(paper "A4")
	(title_block
		(title "timecard-production-celestica-r4006 — R4006-B0001-02_R01.brd")
		(comment 1 "Time Appliance Project (Time Card) / footprints 121-126 of 1113")
	)
	(layers
		(0 "F.Cu" signal "TOP")
		(4 "In1.Cu" signal "L02_GND1")
		(6 "In2.Cu" signal "L03_SIG1")
		(8 "In3.Cu" signal "L04_GND2")
		(10 "In4.Cu" signal "L05_VCC1")
		(12 "In5.Cu" signal "L06_VCC2")
		(14 "In6.Cu" signal "L07_GND3")
		(16 "In7.Cu" signal "L08_SIG2")
		(18 "In8.Cu" signal "L09_GND4")
		(2 "B.Cu" signal "BOTTOM")
		(9 "F.Adhes" user "F.Adhesive")
		(11 "B.Adhes" user "B.Adhesive")
		(13 "F.Paste" user "Package Geometry/Pastemask Top")
		(15 "B.Paste" user "Package Geometry/Pastemask Bottom")
		(5 "F.SilkS" user "Ref Des/Silkscreen Top")
		(7 "B.SilkS" user "Ref Des/Silkscreen Bottom")
		(1 "F.Mask" user "Board Geometry/Soldermask Top")
		(3 "B.Mask" user "Board Geometry/Soldermask Bottom")
		(17 "Dwgs.User" user "User.Drawings")
		(19 "Cmts.User" user "User.Comments")
		(21 "Eco1.User" user "User.Eco1")
		(23 "Eco2.User" user "User.Eco2")
		(25 "Edge.Cuts" user "Board Geometry/Outline")
		(27 "Margin" user)
		(31 "F.CrtYd" user "Package Geometry/Place Bound Top")
		(29 "B.CrtYd" user "Package Geometry/Place Bound Bottom")
		(35 "F.Fab" user "Ref Des/Assembly Top")
		(33 "B.Fab" user "Ref Des/Assembly Bottom")
	)
	(footprint ""
		(layer "F.Cu")
		(at 90.0684 -64.3636 -90)
		(property "Reference" "C279"
			(at -13.1064 9.63803 90)
			(unlocked yes)
			(layer "F.SilkS")
			(effects
				(font
					(size 0.7874 0.5842)
					(thickness 0.1524)
				)
			)
		)
		(property "Value" "VAL*"
			(at 0.0762 2.067306 270)
			(unlocked yes)
			(layer "F.Fab")
			(hide yes)
			(effects
				(font
					(size 0.7874 0.5842)
					(thickness 0.1524)
				)
			)
		)
		(property "Device Type" "CAPACITOR-G105-0B104-EK,0.1UF,A"
			(at 0.0508 1.127506 270)
			(unlocked yes)
			(layer "F.Fab")
			(hide yes)
			(effects
				(font
					(size 0.7874 0.5842)
					(thickness 0.1524)
				)
			)
		)
		(property "User Part Number" "PARTNUM*"
			(at 0.1016 4.023106 270)
			(unlocked yes)
			(layer "Cmts.User")
			(hide yes)
			(effects
				(font
					(size 0.7874 0.5842)
					(thickness 0.1524)
				)
			)
		)
		(property "Tolerance" "TOL*"
			(at 0.0762 3.032506 270)
			(unlocked yes)
			(layer "Cmts.User")
			(hide yes)
			(effects
				(font
					(size 0.7874 0.5842)
					(thickness 0.1524)
				)
			)
		)
		(duplicate_pad_numbers_are_jumpers no)
		(fp_line
			(start -1.143 0.5588)
			(end 1.143 0.5588)
			(stroke
				(width 0.1)
				(type default)
			)
			(layer "F.SilkS")
		)
		(fp_line
			(start 1.143 0.5588)
			(end 1.143 -0.5588)
			(stroke
				(width 0.1)
				(type default)
			)
			(layer "F.SilkS")
		)
		(fp_line
			(start -1.143 -0.5588)
			(end -1.143 0.5588)
			(stroke
				(width 0.1)
				(type default)
			)
			(layer "F.SilkS")
		)
		(fp_line
			(start 1.143 -0.5588)
			(end -1.143 -0.5588)
			(stroke
				(width 0.1)
				(type default)
			)
			(layer "F.SilkS")
		)
		(fp_rect
			(start 1.143 0.5588)
			(end -1.143 -0.5588)
			(stroke
				(width 0)
				(type default)
			)
			(fill no)
			(layer "F.CrtYd")
		)
		(fp_line
			(start -0.508 0.3048)
			(end 0.508 0.3048)
			(stroke
				(width 0.1)
				(type default)
			)
			(layer "F.Fab")
		)
		(fp_line
			(start 0.508 0.3048)
			(end 0.508 -0.3048)
			(stroke
				(width 0.1)
				(type default)
			)
			(layer "F.Fab")
		)
		(fp_line
			(start -0.508 -0.3048)
			(end -0.508 0.3048)
			(stroke
				(width 0.1)
				(type default)
			)
			(layer "F.Fab")
		)
		(fp_line
			(start 0.508 -0.3048)
			(end -0.508 -0.3048)
			(stroke
				(width 0.1)
				(type default)
			)
			(layer "F.Fab")
		)
		(pad "1" smd rect
			(at -0.5334 0 270)
			(size 0.7112 0.6096)
			(layers "F.Cu" "F.Mask" "F.Paste")
			(net "XP3R3V_FPGA")
		)
		(pad "2" smd rect
			(at 0.5334 0 270)
			(size 0.7112 0.6096)
			(layers "F.Cu" "F.Mask" "F.Paste")
			(net "SG")
		)
		(zone
			(layer "F.Cu")
			(hatch none 0.5)
			(connect_pads
				(clearance 0)
			)
			(min_thickness 0.25)
			(keepout
				(tracks allowed)
				(vias not_allowed)
				(pads allowed)
				(copperpour not_allowed)
				(footprints allowed)
			)
			(placement
				(enabled no)
				(sheetname "")
			)
			(fill
				(thermal_gap 0.5)
				(thermal_bridge_width 0.5)
				(island_removal_mode 0)
			)
			(polygon
				(pts
					(xy 89.7636 -64.2874) (xy 90.3732 -64.2874) (xy 90.3732 -64.4398) (xy 89.7636 -64.4398)
				)
			)
		)
	)
	(footprint ""
		(layer "F.Cu")
		(at 20.484592 -71.374 90)
		(property "Reference" "R71"
			(at 0.254 1.144778 90)
			(unlocked yes)
			(layer "F.SilkS")
			(effects
				(font
					(size 0.7874 0.5842)
					(thickness 0.1524)
				)
			)
		)
		(property "Value" "VAL*"
			(at 0.02032 2.13233 90)
			(unlocked yes)
			(layer "F.Fab")
			(hide yes)
			(effects
				(font
					(size 0.7874 0.5842)
					(thickness 0.1524)
				)
			)
		)
		(property "Tolerance" "TOL*"
			(at 0.044704 3.05435 90)
			(unlocked yes)
			(layer "Cmts.User")
			(hide yes)
			(effects
				(font
					(size 0.7874 0.5842)
					(thickness 0.1524)
				)
			)
		)
		(property "User Part Number" "PARTNUM*"
			(at 0.02032 4.024884 90)
			(unlocked yes)
			(layer "Cmts.User")
			(hide yes)
			(effects
				(font
					(size 0.7874 0.5842)
					(thickness 0.1524)
				)
			)
		)
		(property "Device Type" "RESISTOR-G155-14701-01,4.7KOHMA"
			(at 0.008382 1.210564 90)
			(unlocked yes)
			(layer "F.Fab")
			(hide yes)
			(effects
				(font
					(size 0.7874 0.5842)
					(thickness 0.1524)
				)
			)
		)
		(duplicate_pad_numbers_are_jumpers no)
		(fp_line
			(start 1.143 -0.5588)
			(end -1.143 -0.5588)
			(stroke
				(width 0.1)
				(type default)
			)
			(layer "F.SilkS")
		)
		(fp_line
			(start -1.143 -0.5588)
			(end -1.143 0.5588)
			(stroke
				(width 0.1)
				(type default)
			)
			(layer "F.SilkS")
		)
		(fp_line
			(start 1.143 0.5588)
			(end 1.143 -0.5588)
			(stroke
				(width 0.1)
				(type default)
			)
			(layer "F.SilkS")
		)
		(fp_line
			(start -1.143 0.5588)
			(end 1.143 0.5588)
			(stroke
				(width 0.1)
				(type default)
			)
			(layer "F.SilkS")
		)
		(fp_rect
			(start 1.143 -0.5588)
			(end -1.143 0.5588)
			(stroke
				(width 0)
				(type default)
			)
			(fill no)
			(layer "F.CrtYd")
		)
		(fp_line
			(start 0.508 -0.3048)
			(end -0.508 -0.3048)
			(stroke
				(width 0.1)
				(type default)
			)
			(layer "F.Fab")
		)
		(fp_line
			(start -0.508 -0.3048)
			(end -0.508 0.3048)
			(stroke
				(width 0.1)
				(type default)
			)
			(layer "F.Fab")
		)
		(fp_line
			(start 0.508 0.3048)
			(end 0.508 -0.3048)
			(stroke
				(width 0.1)
				(type default)
			)
			(layer "F.Fab")
		)
		(fp_line
			(start -0.508 0.3048)
			(end 0.508 0.3048)
			(stroke
				(width 0.1)
				(type default)
			)
			(layer "F.Fab")
		)
		(pad "1" smd rect
			(at -0.5334 0 90)
			(size 0.7112 0.6096)
			(layers "F.Cu" "F.Mask" "F.Paste")
			(net "XP1R8V_ICP10100")
		)
		(pad "2" smd rect
			(at 0.5334 0 90)
			(size 0.7112 0.6096)
			(layers "F.Cu" "F.Mask" "F.Paste")
			(net "BF_ICP10100_I2C_SCL")
		)
		(zone
			(layer "F.Cu")
			(hatch none 0.5)
			(connect_pads
				(clearance 0)
			)
			(min_thickness 0.25)
			(keepout
				(tracks allowed)
				(vias not_allowed)
				(pads allowed)
				(copperpour not_allowed)
				(footprints allowed)
			)
			(placement
				(enabled no)
				(sheetname "")
			)
			(fill
				(thermal_gap 0.5)
				(thermal_bridge_width 0.5)
				(island_removal_mode 0)
			)
			(polygon
				(pts
					(xy 20.179792 -71.4502) (xy 20.179792 -71.2978) (xy 20.789392 -71.2978) (xy 20.789392 -71.4502)
				)
			)
		)
	)
	(footprint ""
		(layer "F.Cu")
		(at 139.954 -59.436 -90)
		(property "Reference" "C258"
			(at -3.175 1.61163 90)
			(unlocked yes)
			(layer "F.SilkS")
			(effects
				(font
					(size 0.7874 0.5842)
					(thickness 0.1524)
				)
			)
		)
		(property "Value" "VAL*"
			(at 0.193548 2.13614 270)
			(unlocked yes)
			(layer "F.Fab")
			(hide yes)
			(effects
				(font
					(size 0.7874 0.5842)
					(thickness 0.1524)
				)
			)
		)
		(property "Tolerance" "TOL*"
			(at 0.216154 3.1496 270)
			(unlocked yes)
			(layer "Cmts.User")
			(hide yes)
			(effects
				(font
					(size 0.7874 0.5842)
					(thickness 0.1524)
				)
			)
		)
		(property "Device Type" "CAPACITOR-G104-0B103-EK,0.01UFA"
			(at 0.184404 1.180592 270)
			(unlocked yes)
			(layer "F.Fab")
			(hide yes)
			(effects
				(font
					(size 0.7874 0.5842)
					(thickness 0.1524)
				)
			)
		)
		(property "User Part Number" "PARTNUM*"
			(at 0.216154 4.185666 270)
			(unlocked yes)
			(layer "Cmts.User")
			(hide yes)
			(effects
				(font
					(size 0.7874 0.5842)
					(thickness 0.1524)
				)
			)
		)
		(duplicate_pad_numbers_are_jumpers no)
		(fp_line
			(start -0.671322 0.4445)
			(end -0.671322 -0.4445)
			(stroke
				(width 0.1)
				(type default)
			)
			(layer "F.SilkS")
		)
		(fp_line
			(start 0.671322 0.4445)
			(end -0.671322 0.4445)
			(stroke
				(width 0.1)
				(type default)
			)
			(layer "F.SilkS")
		)
		(fp_line
			(start -0.671322 -0.4445)
			(end 0.671322 -0.4445)
			(stroke
				(width 0.1)
				(type default)
			)
			(layer "F.SilkS")
		)
		(fp_line
			(start 0.671322 -0.4445)
			(end 0.671322 0.4445)
			(stroke
				(width 0.1)
				(type default)
			)
			(layer "F.SilkS")
		)
		(fp_rect
			(start 0.671322 0.4445)
			(end -0.671322 -0.4445)
			(stroke
				(width 0)
				(type default)
			)
			(fill no)
			(layer "F.CrtYd")
		)
		(fp_line
			(start -0.31496 0.1651)
			(end 0.31496 0.1651)
			(stroke
				(width 0.1)
				(type default)
			)
			(layer "F.Fab")
		)
		(fp_line
			(start 0.31496 0.1651)
			(end 0.31496 -0.1651)
			(stroke
				(width 0.1)
				(type default)
			)
			(layer "F.Fab")
		)
		(fp_line
			(start -0.31496 -0.1651)
			(end -0.31496 0.1651)
			(stroke
				(width 0.1)
				(type default)
			)
			(layer "F.Fab")
		)
		(fp_line
			(start 0.31496 -0.1651)
			(end -0.31496 -0.1651)
			(stroke
				(width 0.1)
				(type default)
			)
			(layer "F.Fab")
		)
		(pad "1" smd rect
			(at -0.264922 0 270)
			(size 0.3048 0.381)
			(layers "F.Cu" "F.Mask" "F.Paste")
			(net "SG")
		)
		(pad "2" smd rect
			(at 0.264922 0 270)
			(size 0.3048 0.381)
			(layers "F.Cu" "F.Mask" "F.Paste")
			(net "XP1R0V_PG")
		)
		(zone
			(layer "F.Cu")
			(hatch none 0.5)
			(connect_pads
				(clearance 0)
			)
			(min_thickness 0.25)
			(keepout
				(tracks allowed)
				(vias not_allowed)
				(pads allowed)
				(copperpour not_allowed)
				(footprints allowed)
			)
			(placement
				(enabled no)
				(sheetname "")
			)
			(fill
				(thermal_gap 0.5)
				(thermal_bridge_width 0.5)
				(island_removal_mode 0)
			)
			(polygon
				(pts
					(xy 139.7635 -59.323478) (xy 140.1445 -59.323478) (xy 140.1445 -59.548522) (xy 139.7635 -59.548522)
				)
			)
		)
	)
	(footprint ""
		(layer "F.Cu")
		(at 18.415 -82.423 180)
		(property "Reference" "R471"
			(at 0.635 -2.32537 0)
			(unlocked yes)
			(layer "F.SilkS")
			(effects
				(font
					(size 0.7874 0.5842)
					(thickness 0.1524)
				)
			)
		)
		(property "Value" "VAL*"
			(at 0.02032 2.13233 180)
			(unlocked yes)
			(layer "F.Fab")
			(hide yes)
			(effects
				(font
					(size 0.7874 0.5842)
					(thickness 0.1524)
				)
			)
		)
		(property "Tolerance" "TOL*"
			(at 0.044704 3.05435 180)
			(unlocked yes)
			(layer "Cmts.User")
			(hide yes)
			(effects
				(font
					(size 0.7874 0.5842)
					(thickness 0.1524)
				)
			)
		)
		(property "User Part Number" "PARTNUM*"
			(at 0.02032 4.024884 180)
			(unlocked yes)
			(layer "Cmts.User")
			(hide yes)
			(effects
				(font
					(size 0.7874 0.5842)
					(thickness 0.1524)
				)
			)
		)
		(property "Device Type" "RESISTOR-G155-100R0-J0,0OHM,-"
			(at 0.008382 1.210564 180)
			(unlocked yes)
			(layer "F.Fab")
			(hide yes)
			(effects
				(font
					(size 0.7874 0.5842)
					(thickness 0.1524)
				)
			)
		)
		(duplicate_pad_numbers_are_jumpers no)
		(fp_line
			(start 1.143 0.5588)
			(end 1.143 -0.5588)
			(stroke
				(width 0.1)
				(type default)
			)
			(layer "F.SilkS")
		)
		(fp_line
			(start 1.143 -0.5588)
			(end -1.143 -0.5588)
			(stroke
				(width 0.1)
				(type default)
			)
			(layer "F.SilkS")
		)
		(fp_line
			(start -1.143 0.5588)
			(end 1.143 0.5588)
			(stroke
				(width 0.1)
				(type default)
			)
			(layer "F.SilkS")
		)
		(fp_line
			(start -1.143 -0.5588)
			(end -1.143 0.5588)
			(stroke
				(width 0.1)
				(type default)
			)
			(layer "F.SilkS")
		)
		(fp_poly
			(pts
				(xy -1.143 0.5588) (xy 1.143 0.5588) (xy 1.143 -0.5588) (xy -1.143 -0.5588)
			)
			(stroke
				(width 0)
				(type default)
			)
			(fill no)
			(layer "F.CrtYd")
		)
		(fp_line
			(start 0.508 0.3048)
			(end 0.508 -0.3048)
			(stroke
				(width 0.1)
				(type default)
			)
			(layer "F.Fab")
		)
		(fp_line
			(start 0.508 -0.3048)
			(end -0.508 -0.3048)
			(stroke
				(width 0.1)
				(type default)
			)
			(layer "F.Fab")
		)
		(fp_line
			(start -0.508 0.3048)
			(end 0.508 0.3048)
			(stroke
				(width 0.1)
				(type default)
			)
			(layer "F.Fab")
		)
		(fp_line
			(start -0.508 -0.3048)
			(end -0.508 0.3048)
			(stroke
				(width 0.1)
				(type default)
			)
			(layer "F.Fab")
		)
		(pad "1" smd rect
			(at -0.5334 0 180)
			(size 0.7112 0.6096)
			(layers "F.Cu" "F.Mask" "F.Paste")
			(net "R_FT4232_I2C_SCL")
		)
		(pad "2" smd rect
			(at 0.5334 0 180)
			(size 0.7112 0.6096)
			(layers "F.Cu" "F.Mask" "F.Paste")
			(net "FT4232_I2C_SCL")
		)
		(zone
			(layer "F.Cu")
			(hatch none 0.5)
			(connect_pads
				(clearance 0)
			)
			(min_thickness 0.25)
			(keepout
				(tracks not_allowed)
				(vias allowed)
				(pads allowed)
				(copperpour not_allowed)
				(footprints allowed)
			)
			(placement
				(enabled no)
				(sheetname "")
			)
			(fill
				(thermal_gap 0.5)
				(thermal_bridge_width 0.5)
				(island_removal_mode 0)
			)
			(polygon
				(pts
					(xy 18.4912 -82.7278) (xy 18.3388 -82.7278) (xy 18.3388 -82.1182) (xy 18.4912 -82.1182)
				)
			)
		)
		(zone
			(layer "F.Cu")
			(hatch none 0.5)
			(connect_pads
				(clearance 0)
			)
			(min_thickness 0.25)
			(keepout
				(tracks allowed)
				(vias not_allowed)
				(pads allowed)
				(copperpour not_allowed)
				(footprints allowed)
			)
			(placement
				(enabled no)
				(sheetname "")
			)
			(fill
				(thermal_gap 0.5)
				(thermal_bridge_width 0.5)
				(island_removal_mode 0)
			)
			(polygon
				(pts
					(xy 18.4912 -82.7278) (xy 18.3388 -82.7278) (xy 18.3388 -82.1182) (xy 18.4912 -82.1182)
				)
			)
		)
	)
	(footprint ""
		(layer "F.Cu")
		(at 106.807 -58.293)
		(property "Reference" "TP187"
			(at 3.20675 2.0828 90)
			(unlocked yes)
			(layer "F.SilkS")
			(effects
				(font
					(size 0.635 0.4064)
					(thickness 0.1524)
				)
				(justify left)
			)
		)
		(property "Value" ""
			(at 0 0 0)
			(layer "F.Fab")
			(effects
				(font
					(size 1.27 1.27)
				)
			)
		)
		(property "Device Type" "TP_PIONT-TP010CT020B030_PTH-TPA"
			(at -1.341882 0.996696 0)
			(unlocked yes)
			(layer "F.Fab")
			(hide yes)
			(effects
				(font
					(size 0.7874 0.5842)
					(thickness 0.1524)
				)
				(justify left)
			)
		)
		(duplicate_pad_numbers_are_jumpers no)
		(fp_poly
			(pts
				(arc
					(start 0.889 0)
					(mid -0.889 0)
					(end 0.889 0)
				)
			)
			(stroke
				(width 0)
				(type default)
			)
			(fill no)
			(layer "B.CrtYd")
		)
		(fp_poly
			(pts
				(arc
					(start 0.889 0)
					(mid -0.889 0)
					(end 0.889 0)
				)
			)
			(stroke
				(width 0)
				(type default)
			)
			(fill no)
			(layer "F.CrtYd")
		)
		(pad "1" thru_hole circle
			(at 0 0)
			(size 0.508 0.508)
			(drill 0.254)
			(layers "*.Cu" "*.Mask")
			(remove_unused_layers no)
			(net "IO_L24P_16")
			(clearance 0.1016)
			(padstack
				(mode front_inner_back)
				(layer "Inner"
					(shape circle)
					(size 0.508 0.508)
					(clearance 0.1016)
				)
				(layer "B.Cu"
					(shape circle)
					(size 0.762 0.762)
					(clearance -0.0254)
				)
			)
		)
	)
	(footprint ""
		(layer "F.Cu")
		(at 81.0006 -53.594 180)
		(property "Reference" "R83"
			(at 0.9906 -14.64437 0)
			(unlocked yes)
			(layer "F.SilkS")
			(effects
				(font
					(size 0.7874 0.5842)
					(thickness 0.1524)
				)
			)
		)
		(property "Value" "VAL*"
			(at 0.02032 2.13233 180)
			(unlocked yes)
			(layer "F.Fab")
			(hide yes)
			(effects
				(font
					(size 0.7874 0.5842)
					(thickness 0.1524)
				)
			)
		)
		(property "Device Type" "RESISTOR-G155-100R0-J0,0OHM,-"
			(at 0.008382 1.210564 180)
			(unlocked yes)
			(layer "F.Fab")
			(hide yes)
			(effects
				(font
					(size 0.7874 0.5842)
					(thickness 0.1524)
				)
			)
		)
		(property "User Part Number" "PARTNUM*"
			(at 0.02032 4.024884 180)
			(unlocked yes)
			(layer "Cmts.User")
			(hide yes)
			(effects
				(font
					(size 0.7874 0.5842)
					(thickness 0.1524)
				)
			)
		)
		(property "Tolerance" "TOL*"
			(at 0.044704 3.05435 180)
			(unlocked yes)
			(layer "Cmts.User")
			(hide yes)
			(effects
				(font
					(size 0.7874 0.5842)
					(thickness 0.1524)
				)
			)
		)
		(duplicate_pad_numbers_are_jumpers no)
		(fp_line
			(start 1.143 0.5588)
			(end 1.143 -0.5588)
			(stroke
				(width 0.1)
				(type default)
			)
			(layer "F.SilkS")
		)
		(fp_line
			(start 1.143 -0.5588)
			(end -1.143 -0.5588)
			(stroke
				(width 0.1)
				(type default)
			)
			(layer "F.SilkS")
		)
		(fp_line
			(start -1.143 0.5588)
			(end 1.143 0.5588)
			(stroke
				(width 0.1)
				(type default)
			)
			(layer "F.SilkS")
		)
		(fp_line
			(start -1.143 -0.5588)
			(end -1.143 0.5588)
			(stroke
				(width 0.1)
				(type default)
			)
			(layer "F.SilkS")
		)
		(fp_rect
			(start 1.143 -0.5588)
			(end -1.143 0.5588)
			(stroke
				(width 0)
				(type default)
			)
			(fill no)
			(layer "F.CrtYd")
		)
		(fp_line
			(start 0.508 0.3048)
			(end 0.508 -0.3048)
			(stroke
				(width 0.1)
				(type default)
			)
			(layer "F.Fab")
		)
		(fp_line
			(start 0.508 -0.3048)
			(end -0.508 -0.3048)
			(stroke
				(width 0.1)
				(type default)
			)
			(layer "F.Fab")
		)
		(fp_line
			(start -0.508 0.3048)
			(end 0.508 0.3048)
			(stroke
				(width 0.1)
				(type default)
			)
			(layer "F.Fab")
		)
		(fp_line
			(start -0.508 -0.3048)
			(end -0.508 0.3048)
			(stroke
				(width 0.1)
				(type default)
			)
			(layer "F.Fab")
		)
		(pad "1" smd rect
			(at -0.5334 0 180)
			(size 0.7112 0.6096)
			(layers "F.Cu" "F.Mask" "F.Paste")
			(net "FPGA_OUT_MAC_PPS_IN1P")
		)
		(pad "2" smd rect
			(at 0.5334 0 180)
			(size 0.7112 0.6096)
			(layers "F.Cu" "F.Mask" "F.Paste")
			(net "R_MAC_PPS_IN1P")
		)
		(zone
			(layer "F.Cu")
			(hatch none 0.5)
			(connect_pads
				(clearance 0)
			)
			(min_thickness 0.25)
			(keepout
				(tracks allowed)
				(vias not_allowed)
				(pads allowed)
				(copperpour not_allowed)
				(footprints allowed)
			)
			(placement
				(enabled no)
				(sheetname "")
			)
			(fill
				(thermal_gap 0.5)
				(thermal_bridge_width 0.5)
				(island_removal_mode 0)
			)
			(polygon
				(pts
					(xy 80.9244 -53.2892) (xy 81.0768 -53.2892) (xy 81.0768 -53.8988) (xy 80.9244 -53.8988)
				)
			)
		)
	)
)
